# S9S_MB_2U (Grand Teton) — schematic netlist excerpt (pin names and nets, part order shuffled) for the footprints in the layout excerpt that follows; sources: Cadence DE-HDL packaged netlist, KiCad conversion of 03242023_DA0F0TMBIJ0_F0T_Motherboard_J_brd_V01_OCP.brd

R4107  Q_RES  10K 1% CHIP  pkg 0402LF  page 184 : A = PD_GPP_I_17 ; B = GND
R184  Q_RES  100 1% CHIP  pkg 0402LF  page 124 : A = PWRGD_CPU0_BUF_R ; B = PWRGD_CPU0_LVC1

(kicad_pcb
	(version 20260206)
	(generator "pcbnew")
	(generator_version "10.0")
	(general
		(thickness 1.6)
		(legacy_teardrops no)
	)
	(paper "A4")
	(title_block
		(title "03242023_DA0F0TMBIJ0_F0T_Motherboard_J_brd_V01_OCP.brd")
		(comment 1 "Grand Teton / footprints 5889-5890 of 6105")
	)
	(layers
		(0 "F.Cu" signal "TOP")
		(4 "In1.Cu" signal "GND")
		(6 "In2.Cu" signal "IN1")
		(8 "In3.Cu" signal "GND1")
		(10 "In4.Cu" signal "IN2")
		(12 "In5.Cu" signal "GND2")
		(14 "In6.Cu" signal "IN3")
		(16 "In7.Cu" signal "GND3")
		(18 "In8.Cu" signal "VCC")
		(20 "In9.Cu" signal "VCC1")
		(22 "In10.Cu" signal "GND4")
		(24 "In11.Cu" signal "IN4")
		(26 "In12.Cu" signal "GND5")
		(28 "In13.Cu" signal "IN5")
		(30 "In14.Cu" signal "GND6")
		(32 "In15.Cu" signal "IN6")
		(34 "In16.Cu" signal "GND7")
		(2 "B.Cu" signal "BOTTOM")
		(9 "F.Adhes" user "F.Adhesive")
		(11 "B.Adhes" user "B.Adhesive")
		(13 "F.Paste" user "Package Geometry/Pastemask Top")
		(15 "B.Paste" user "Package Geometry/Pastemask Bottom")
		(5 "F.SilkS" user "Ref Des/Silkscreen Top")
		(7 "B.SilkS" user "Ref Des/Silkscreen Bottom")
		(1 "F.Mask" user "Board Geometry/Soldermask Top")
		(3 "B.Mask" user "Board Geometry/Soldermask Bottom")
		(17 "Dwgs.User" user "User.Drawings")
		(19 "Cmts.User" user "User.Comments")
		(21 "Eco1.User" user "User.Eco1")
		(23 "Eco2.User" user "User.Eco2")
		(25 "Edge.Cuts" user "Board Geometry/Outline")
		(27 "Margin" user)
		(31 "F.CrtYd" user "Package Geometry/Place Bound Top")
		(29 "B.CrtYd" user "Package Geometry/Place Bound Bottom")
		(35 "F.Fab" user "Ref Des/Assembly Top")
		(33 "B.Fab" user "Ref Des/Assembly Bottom")
	)
	(footprint ""
		(layer "B.Cu")
		(at 330.577698 -190.82893 -90)
		(property "Reference" "R184"
			(at 0 0 90)
			(layer "B.SilkS")
			(hide yes)
			(effects
				(font
					(size 1.27 1.27)
				)
				(justify mirror)
			)
		)
		(property "Value" ""
			(at 0 0 90)
			(layer "B.Fab")
			(effects
				(font
					(size 1.27 1.27)
				)
				(justify mirror)
			)
		)
		(duplicate_pad_numbers_are_jumpers no)
		(fp_line
			(start -0.7874 0.4064)
			(end 0.7874 0.4064)
			(stroke
				(width 0.1524)
				(type default)
			)
			(layer "B.SilkS")
		)
		(fp_line
			(start 0.7874 0.4064)
			(end 0.7874 -0.4064)
			(stroke
				(width 0.1524)
				(type default)
			)
			(layer "B.SilkS")
		)
		(fp_line
			(start -0.7874 -0.4064)
			(end -0.7874 0.4064)
			(stroke
				(width 0.1524)
				(type default)
			)
			(layer "B.SilkS")
		)
		(fp_line
			(start 0.7874 -0.4064)
			(end -0.7874 -0.4064)
			(stroke
				(width 0.1524)
				(type default)
			)
			(layer "B.SilkS")
		)
		(fp_line
			(start -0.67945 0.3048)
			(end -0.120396 0.3048)
			(stroke
				(width 0.1)
				(type default)
			)
			(layer "B.Fab")
		)
		(fp_line
			(start -0.120396 0.3048)
			(end -0.120396 0.2794)
			(stroke
				(width 0.1)
				(type default)
			)
			(layer "B.Fab")
		)
		(fp_line
			(start 0.12065 0.3048)
			(end 0.67945 0.3048)
			(stroke
				(width 0.1)
				(type default)
			)
			(layer "B.Fab")
		)
		(fp_line
			(start 0.67945 0.3048)
			(end 0.67945 -0.305054)
			(stroke
				(width 0.1)
				(type default)
			)
			(layer "B.Fab")
		)
		(fp_line
			(start -0.120396 0.2794)
			(end 0.12065 0.2794)
			(stroke
				(width 0.1)
				(type default)
			)
			(layer "B.Fab")
		)
		(fp_line
			(start 0.12065 0.2794)
			(end 0.12065 0.3048)
			(stroke
				(width 0.1)
				(type default)
			)
			(layer "B.Fab")
		)
		(fp_line
			(start -0.12065 -0.2794)
			(end -0.12065 -0.3048)
			(stroke
				(width 0.1)
				(type default)
			)
			(layer "B.Fab")
		)
		(fp_line
			(start 0.12065 -0.2794)
			(end -0.12065 -0.2794)
			(stroke
				(width 0.1)
				(type default)
			)
			(layer "B.Fab")
		)
		(fp_line
			(start -0.67945 -0.3048)
			(end -0.67945 0.3048)
			(stroke
				(width 0.1)
				(type default)
			)
			(layer "B.Fab")
		)
		(fp_line
			(start -0.12065 -0.3048)
			(end -0.67945 -0.3048)
			(stroke
				(width 0.1)
				(type default)
			)
			(layer "B.Fab")
		)
		(fp_line
			(start 0.12065 -0.305054)
			(end 0.12065 -0.2794)
			(stroke
				(width 0.1)
				(type default)
			)
			(layer "B.Fab")
		)
		(fp_line
			(start 0.67945 -0.305054)
			(end 0.12065 -0.305054)
			(stroke
				(width 0.1)
				(type default)
			)
			(layer "B.Fab")
		)
		(pad "1" smd circle
			(at 0.40005 0 90)
			(size 0 0)
			(layers "B.Cu" "B.Mask" "B.Paste")
			(net "PWRGD_CPU0_BUF_R")
		)
		(pad "2" smd circle
			(at -0.40005 0 90)
			(size 0 0)
			(layers "B.Cu" "B.Mask" "B.Paste")
			(net "PWRGD_CPU0_LVC1")
		)
	)
	(footprint ""
		(layer "B.Cu")
		(at 315.110622 -52.187348)
		(property "Reference" "R4107"
			(at 0 0 0)
			(layer "B.SilkS")
			(hide yes)
			(effects
				(font
					(size 1.27 1.27)
				)
				(justify mirror)
			)
		)
		(property "Value" ""
			(at 0 0 0)
			(layer "B.Fab")
			(effects
				(font
					(size 1.27 1.27)
				)
				(justify mirror)
			)
		)
		(duplicate_pad_numbers_are_jumpers no)
		(fp_line
			(start -0.7874 -0.4064)
			(end -0.7874 0.4064)
			(stroke
				(width 0.1524)
				(type default)
			)
			(layer "B.SilkS")
		)
		(fp_line
			(start -0.7874 0.4064)
			(end 0.7874 0.4064)
			(stroke
				(width 0.1524)
				(type default)
			)
			(layer "B.SilkS")
		)
		(fp_line
			(start 0.7874 -0.4064)
			(end -0.7874 -0.4064)
			(stroke
				(width 0.1524)
				(type default)
			)
			(layer "B.SilkS")
		)
		(fp_line
			(start 0.7874 0.4064)
			(end 0.7874 -0.4064)
			(stroke
				(width 0.1524)
				(type default)
			)
			(layer "B.SilkS")
		)
		(fp_line
			(start -0.67945 -0.3048)
			(end -0.67945 0.3048)
			(stroke
				(width 0.1)
				(type default)
			)
			(layer "B.Fab")
		)
		(fp_line
			(start -0.67945 0.3048)
			(end -0.120396 0.3048)
			(stroke
				(width 0.1)
				(type default)
			)
			(layer "B.Fab")
		)
		(fp_line
			(start -0.12065 -0.3048)
			(end -0.67945 -0.3048)
			(stroke
				(width 0.1)
				(type default)
			)
			(layer "B.Fab")
		)
		(fp_line
			(start -0.12065 -0.2794)
			(end -0.12065 -0.3048)
			(stroke
				(width 0.1)
				(type default)
			)
			(layer "B.Fab")
		)
		(fp_line
			(start -0.120396 0.2794)
			(end 0.12065 0.2794)
			(stroke
				(width 0.1)
				(type default)
			)
			(layer "B.Fab")
		)
		(fp_line
			(start -0.120396 0.3048)
			(end -0.120396 0.2794)
			(stroke
				(width 0.1)
				(type default)
			)
			(layer "B.Fab")
		)
		(fp_line
			(start 0.12065 -0.305054)
			(end 0.12065 -0.2794)
			(stroke
				(width 0.1)
				(type default)
			)
			(layer "B.Fab")
		)
		(fp_line
			(start 0.12065 -0.2794)
			(end -0.12065 -0.2794)
			(stroke
				(width 0.1)
				(type default)
			)
			(layer "B.Fab")
		)
		(fp_line
			(start 0.12065 0.2794)
			(end 0.12065 0.3048)
			(stroke
				(width 0.1)
				(type default)
			)
			(layer "B.Fab")
		)
		(fp_line
			(start 0.12065 0.3048)
			(end 0.67945 0.3048)
			(stroke
				(width 0.1)
				(type default)
			)
			(layer "B.Fab")
		)
		(fp_line
			(start 0.67945 -0.305054)
			(end 0.12065 -0.305054)
			(stroke
				(width 0.1)
				(type default)
			)
			(layer "B.Fab")
		)
		(fp_line
			(start 0.67945 0.3048)
			(end 0.67945 -0.305054)
			(stroke
				(width 0.1)
				(type default)
			)
			(layer "B.Fab")
		)
		(pad "1" smd circle
			(at 0.40005 0 180)
			(size 0 0)
			(layers "B.Cu" "B.Mask" "B.Paste")
			(net "PD_GPP_I_17")
		)
		(pad "2" smd circle
			(at -0.40005 0 180)
			(size 0 0)
			(layers "B.Cu" "B.Mask" "B.Paste")
			(net "GND")
		)
	)
)
